(kicad_pcb
	(version 20260206)
	(generator "pcbnew")
	(generator_version "10.0")
	(general
		(thickness 1.6)
		(legacy_teardrops no)
	)
	(paper "A4")
	(title_block
		(title "01162023_DA0F0TEBIF0_F0T_Expander_BD_F_brd_V02_OCP.brd")
		(comment 1 "Grand Teton / footprints 8844-8849 of 9728")
	)
	(layers
		(0 "F.Cu" signal "TOP")
		(4 "In1.Cu" signal "GND")
		(6 "In2.Cu" signal "VCC")
		(8 "In3.Cu" signal "VCC1")
		(10 "In4.Cu" signal "GND1")
		(12 "In5.Cu" signal "IN1")
		(14 "In6.Cu" signal "GND2")
		(16 "In7.Cu" signal "IN2")
		(18 "In8.Cu" signal "GND3")
		(20 "In9.Cu" signal "IN3")
		(22 "In10.Cu" signal "GND4")
		(24 "In11.Cu" signal "IN4")
		(26 "In12.Cu" signal "GND5")
		(28 "In13.Cu" signal "IN5")
		(30 "In14.Cu" signal "GND6")
		(32 "In15.Cu" signal "IN6")
		(34 "In16.Cu" signal "GND7")
		(2 "B.Cu" signal "BOTTOM")
		(9 "F.Adhes" user "F.Adhesive")
		(11 "B.Adhes" user "B.Adhesive")
		(13 "F.Paste" user "Package Geometry/Pastemask Top")
		(15 "B.Paste" user "Package Geometry/Pastemask Bottom")
		(5 "F.SilkS" user "Ref Des/Silkscreen Top")
		(7 "B.SilkS" user "Ref Des/Silkscreen Bottom")
		(1 "F.Mask" user "Board Geometry/Soldermask Top")
		(3 "B.Mask" user "Board Geometry/Soldermask Bottom")
		(17 "Dwgs.User" user "User.Drawings")
		(19 "Cmts.User" user "User.Comments")
		(21 "Eco1.User" user "User.Eco1")
		(23 "Eco2.User" user "User.Eco2")
		(25 "Edge.Cuts" user "Board Geometry/Outline")
		(27 "Margin" user)
		(31 "F.CrtYd" user "Package Geometry/Place Bound Top")
		(29 "B.CrtYd" user "Package Geometry/Place Bound Bottom")
		(35 "F.Fab" user "Ref Des/Assembly Top")
		(33 "B.Fab" user "Ref Des/Assembly Bottom")
	)
	(footprint ""
		(layer "B.Cu")
		(at 358.278684 -282.040584 90)
		(property "Reference" "PR158"
			(at 0 0 90)
			(layer "B.SilkS")
			(hide yes)
			(effects
				(font
					(size 1.27 1.27)
				)
				(justify mirror)
			)
		)
		(property "Value" ""
			(at 0 0 90)
			(layer "B.Fab")
			(effects
				(font
					(size 1.27 1.27)
				)
				(justify mirror)
			)
		)
		(duplicate_pad_numbers_are_jumpers no)
		(fp_line
			(start 0.7874 -0.4064)
			(end -0.7874 -0.4064)
			(stroke
				(width 0.1524)
				(type default)
			)
			(layer "B.SilkS")
		)
		(fp_line
			(start -0.7874 -0.4064)
			(end -0.7874 0.4064)
			(stroke
				(width 0.1524)
				(type default)
			)
			(layer "B.SilkS")
		)
		(fp_line
			(start 0.7874 0.4064)
			(end 0.7874 -0.4064)
			(stroke
				(width 0.1524)
				(type default)
			)
			(layer "B.SilkS")
		)
		(fp_line
			(start -0.7874 0.4064)
			(end 0.7874 0.4064)
			(stroke
				(width 0.1524)
				(type default)
			)
			(layer "B.SilkS")
		)
		(fp_line
			(start 0.67945 -0.305054)
			(end 0.12065 -0.305054)
			(stroke
				(width 0.1)
				(type default)
			)
			(layer "B.Fab")
		)
		(fp_line
			(start 0.12065 -0.305054)
			(end 0.12065 -0.2794)
			(stroke
				(width 0.1)
				(type default)
			)
			(layer "B.Fab")
		)
		(fp_line
			(start -0.12065 -0.3048)
			(end -0.67945 -0.3048)
			(stroke
				(width 0.1)
				(type default)
			)
			(layer "B.Fab")
		)
		(fp_line
			(start -0.67945 -0.3048)
			(end -0.67945 0.3048)
			(stroke
				(width 0.1)
				(type default)
			)
			(layer "B.Fab")
		)
		(fp_line
			(start 0.12065 -0.2794)
			(end -0.12065 -0.2794)
			(stroke
				(width 0.1)
				(type default)
			)
			(layer "B.Fab")
		)
		(fp_line
			(start -0.12065 -0.2794)
			(end -0.12065 -0.3048)
			(stroke
				(width 0.1)
				(type default)
			)
			(layer "B.Fab")
		)
		(fp_line
			(start 0.12065 0.2794)
			(end 0.12065 0.3048)
			(stroke
				(width 0.1)
				(type default)
			)
			(layer "B.Fab")
		)
		(fp_line
			(start -0.120396 0.2794)
			(end 0.12065 0.2794)
			(stroke
				(width 0.1)
				(type default)
			)
			(layer "B.Fab")
		)
		(fp_line
			(start 0.67945 0.3048)
			(end 0.67945 -0.305054)
			(stroke
				(width 0.1)
				(type default)
			)
			(layer "B.Fab")
		)
		(fp_line
			(start 0.12065 0.3048)
			(end 0.67945 0.3048)
			(stroke
				(width 0.1)
				(type default)
			)
			(layer "B.Fab")
		)
		(fp_line
			(start -0.120396 0.3048)
			(end -0.120396 0.2794)
			(stroke
				(width 0.1)
				(type default)
			)
			(layer "B.Fab")
		)
		(fp_line
			(start -0.67945 0.3048)
			(end -0.120396 0.3048)
			(stroke
				(width 0.1)
				(type default)
			)
			(layer "B.Fab")
		)
		(pad "1" smd circle
			(at 0.40005 0 270)
			(size 0 0)
			(layers "B.Cu" "B.Mask" "B.Paste")
			(net "SW_P0V8_PEX3_VOS1")
		)
		(pad "2" smd circle
			(at -0.40005 0 270)
			(size 0 0)
			(layers "B.Cu" "B.Mask" "B.Paste")
			(net "P0V8_PEX3")
		)
	)
	(footprint ""
		(layer "B.Cu")
		(at 286.149796 -303.499774 -90)
		(property "Reference" "C3261"
			(at 0 0 90)
			(layer "B.SilkS")
			(hide yes)
			(effects
				(font
					(size 1.27 1.27)
				)
				(justify mirror)
			)
		)
		(property "Value" ""
			(at 0 0 90)
			(layer "B.Fab")
			(effects
				(font
					(size 1.27 1.27)
				)
				(justify mirror)
			)
		)
		(duplicate_pad_numbers_are_jumpers no)
		(fp_line
			(start -0.299974 0.150114)
			(end 0.299974 0.150114)
			(stroke
				(width 0.1)
				(type default)
			)
			(layer "B.Fab")
		)
		(fp_line
			(start 0.299974 0.150114)
			(end 0.299974 -0.150114)
			(stroke
				(width 0.1)
				(type default)
			)
			(layer "B.Fab")
		)
		(fp_line
			(start -0.299974 -0.150114)
			(end -0.299974 0.150114)
			(stroke
				(width 0.1)
				(type default)
			)
			(layer "B.Fab")
		)
		(fp_line
			(start 0.299974 -0.150114)
			(end -0.299974 -0.150114)
			(stroke
				(width 0.1)
				(type default)
			)
			(layer "B.Fab")
		)
		(pad "1" smd rect
			(at 0.2667 0 90)
			(size 0.3048 0.381)
			(layers "B.Cu" "B.Mask" "B.Paste")
			(net "P1V25_PEX2")
		)
		(pad "2" smd rect
			(at -0.2667 0 90)
			(size 0.3048 0.381)
			(layers "B.Cu" "B.Mask" "B.Paste")
			(net "GND")
		)
	)
	(footprint ""
		(layer "B.Cu")
		(at 327.78827 -227.943664 180)
		(property "Reference" "R5641"
			(at 0 0 0)
			(layer "B.SilkS")
			(hide yes)
			(effects
				(font
					(size 1.27 1.27)
				)
				(justify mirror)
			)
		)
		(property "Value" ""
			(at 0 0 0)
			(layer "B.Fab")
			(effects
				(font
					(size 1.27 1.27)
				)
				(justify mirror)
			)
		)
		(duplicate_pad_numbers_are_jumpers no)
		(fp_line
			(start 1.2954 0.5842)
			(end 1.2954 -0.5842)
			(stroke
				(width 0.1524)
				(type default)
			)
			(layer "B.SilkS")
		)
		(fp_line
			(start 1.2954 -0.5842)
			(end -1.2954 -0.5842)
			(stroke
				(width 0.1524)
				(type default)
			)
			(layer "B.SilkS")
		)
		(fp_line
			(start -1.2954 0.5842)
			(end 1.2954 0.5842)
			(stroke
				(width 0.1524)
				(type default)
			)
			(layer "B.SilkS")
		)
		(fp_line
			(start -1.2954 -0.5842)
			(end -1.2954 0.5842)
			(stroke
				(width 0.1524)
				(type default)
			)
			(layer "B.SilkS")
		)
		(fp_line
			(start 1.1938 0.4064)
			(end 1.1938 -0.406654)
			(stroke
				(width 0.1)
				(type default)
			)
			(layer "B.Fab")
		)
		(fp_line
			(start 1.1938 -0.406654)
			(end 0.8636 -0.406654)
			(stroke
				(width 0.1)
				(type default)
			)
			(layer "B.Fab")
		)
		(fp_line
			(start 0.8636 0.4572)
			(end 0.8636 0.4318)
			(stroke
				(width 0.1)
				(type default)
			)
			(layer "B.Fab")
		)
		(fp_line
			(start 0.8636 0.4318)
			(end 0.8636 0.4064)
			(stroke
				(width 0.1)
				(type default)
			)
			(layer "B.Fab")
		)
		(fp_line
			(start 0.8636 0.4064)
			(end 1.1938 0.4064)
			(stroke
				(width 0.1)
				(type default)
			)
			(layer "B.Fab")
		)
		(fp_line
			(start 0.8636 -0.406654)
			(end 0.8636 -0.4572)
			(stroke
				(width 0.1)
				(type default)
			)
			(layer "B.Fab")
		)
		(fp_line
			(start 0.8636 -0.4572)
			(end -0.8636 -0.4572)
			(stroke
				(width 0.1)
				(type default)
			)
			(layer "B.Fab")
		)
		(fp_line
			(start -0.8636 0.4572)
			(end 0.8636 0.4572)
			(stroke
				(width 0.1)
				(type default)
			)
			(layer "B.Fab")
		)
		(fp_line
			(start -0.8636 0.4064)
			(end -0.8636 0.4572)
			(stroke
				(width 0.1)
				(type default)
			)
			(layer "B.Fab")
		)
		(fp_line
			(start -0.8636 -0.406654)
			(end -1.1938 -0.406654)
			(stroke
				(width 0.1)
				(type default)
			)
			(layer "B.Fab")
		)
		(fp_line
			(start -0.8636 -0.4572)
			(end -0.8636 -0.406654)
			(stroke
				(width 0.1)
				(type default)
			)
			(layer "B.Fab")
		)
		(fp_line
			(start -1.1938 0.4064)
			(end -0.8636 0.4064)
			(stroke
				(width 0.1)
				(type default)
			)
			(layer "B.Fab")
		)
		(fp_line
			(start -1.1938 -0.406654)
			(end -1.1938 0.4064)
			(stroke
				(width 0.1)
				(type default)
			)
			(layer "B.Fab")
		)
		(pad "1" smd rect
			(at 0.7366 0 90)
			(size 0.7112 0.8128)
			(layers "B.Cu" "B.Mask" "B.Paste")
			(net "P3V3_AUX")
		)
		(pad "2" smd rect
			(at -0.7366 0 90)
			(size 0.7112 0.8128)
			(layers "B.Cu" "B.Mask" "B.Paste")
			(net "P3V3_FPGA_VCCIO5")
		)
	)
	(footprint ""
		(layer "B.Cu")
		(at 62.180216 -295.221914)
		(property "Reference" "C1102"
			(at 0 0 0)
			(layer "B.SilkS")
			(hide yes)
			(effects
				(font
					(size 1.27 1.27)
				)
				(justify mirror)
			)
		)
		(property "Value" ""
			(at 0 0 0)
			(layer "B.Fab")
			(effects
				(font
					(size 1.27 1.27)
				)
				(justify mirror)
			)
		)
		(duplicate_pad_numbers_are_jumpers no)
		(fp_line
			(start -1.2954 -0.5842)
			(end -1.2954 0.5842)
			(stroke
				(width 0.1524)
				(type default)
			)
			(layer "B.SilkS")
		)
		(fp_line
			(start -1.2954 0.5842)
			(end 1.2954 0.5842)
			(stroke
				(width 0.1524)
				(type default)
			)
			(layer "B.SilkS")
		)
		(fp_line
			(start 1.2954 -0.5842)
			(end -1.2954 -0.5842)
			(stroke
				(width 0.1524)
				(type default)
			)
			(layer "B.SilkS")
		)
		(fp_line
			(start 1.2954 0.5842)
			(end 1.2954 -0.5842)
			(stroke
				(width 0.1524)
				(type default)
			)
			(layer "B.SilkS")
		)
		(fp_line
			(start -1.1938 -0.4064)
			(end -1.1938 0.4064)
			(stroke
				(width 0.1)
				(type default)
			)
			(layer "B.Fab")
		)
		(fp_line
			(start -1.1938 0.4064)
			(end -0.8636 0.4064)
			(stroke
				(width 0.1)
				(type default)
			)
			(layer "B.Fab")
		)
		(fp_line
			(start -0.8636 -0.4572)
			(end -0.8636 -0.4064)
			(stroke
				(width 0.1)
				(type default)
			)
			(layer "B.Fab")
		)
		(fp_line
			(start -0.8636 -0.4064)
			(end -1.1938 -0.4064)
			(stroke
				(width 0.1)
				(type default)
			)
			(layer "B.Fab")
		)
		(fp_line
			(start -0.8636 0.4064)
			(end -0.8636 0.4572)
			(stroke
				(width 0.1)
				(type default)
			)
			(layer "B.Fab")
		)
		(fp_line
			(start -0.8636 0.4572)
			(end 0.8636 0.4572)
			(stroke
				(width 0.1)
				(type default)
			)
			(layer "B.Fab")
		)
		(fp_line
			(start 0.8636 -0.4572)
			(end -0.8636 -0.4572)
			(stroke
				(width 0.1)
				(type default)
			)
			(layer "B.Fab")
		)
		(fp_line
			(start 0.8636 -0.4064)
			(end 0.8636 -0.4572)
			(stroke
				(width 0.1)
				(type default)
			)
			(layer "B.Fab")
		)
		(fp_line
			(start 0.8636 0.4064)
			(end 1.1938 0.4064)
			(stroke
				(width 0.1)
				(type default)
			)
			(layer "B.Fab")
		)
		(fp_line
			(start 0.8636 0.4572)
			(end 0.8636 0.4064)
			(stroke
				(width 0.1)
				(type default)
			)
			(layer "B.Fab")
		)
		(fp_line
			(start 1.1938 -0.4064)
			(end 0.8636 -0.4064)
			(stroke
				(width 0.1)
				(type default)
			)
			(layer "B.Fab")
		)
		(fp_line
			(start 1.1938 0.4064)
			(end 1.1938 -0.4064)
			(stroke
				(width 0.1)
				(type default)
			)
			(layer "B.Fab")
		)
		(pad "1" smd rect
			(at 0.7366 0 270)
			(size 0.7112 0.8128)
			(layers "B.Cu" "B.Mask" "B.Paste")
			(net "P0V8_PEX0")
		)
		(pad "2" smd rect
			(at -0.7366 0 270)
			(size 0.7112 0.8128)
			(layers "B.Cu" "B.Mask" "B.Paste")
			(net "GND")
		)
	)
	(footprint ""
		(layer "B.Cu")
		(at 51.099974 -303.499774 -90)
		(property "Reference" "C2914"
			(at 0 0 90)
			(layer "B.SilkS")
			(hide yes)
			(effects
				(font
					(size 1.27 1.27)
				)
				(justify mirror)
			)
		)
		(property "Value" ""
			(at 0 0 90)
			(layer "B.Fab")
			(effects
				(font
					(size 1.27 1.27)
				)
				(justify mirror)
			)
		)
		(duplicate_pad_numbers_are_jumpers no)
		(fp_line
			(start -0.299974 0.150114)
			(end 0.299974 0.150114)
			(stroke
				(width 0.1)
				(type default)
			)
			(layer "B.Fab")
		)
		(fp_line
			(start 0.299974 0.150114)
			(end 0.299974 -0.150114)
			(stroke
				(width 0.1)
				(type default)
			)
			(layer "B.Fab")
		)
		(fp_line
			(start -0.299974 -0.150114)
			(end -0.299974 0.150114)
			(stroke
				(width 0.1)
				(type default)
			)
			(layer "B.Fab")
		)
		(fp_line
			(start 0.299974 -0.150114)
			(end -0.299974 -0.150114)
			(stroke
				(width 0.1)
				(type default)
			)
			(layer "B.Fab")
		)
		(pad "1" smd rect
			(at 0.2667 0 90)
			(size 0.3048 0.381)
			(layers "B.Cu" "B.Mask" "B.Paste")
			(net "P1V25_PEX0")
		)
		(pad "2" smd rect
			(at -0.2667 0 90)
			(size 0.3048 0.381)
			(layers "B.Cu" "B.Mask" "B.Paste")
			(net "GND")
		)
	)
	(footprint ""
		(layer "B.Cu")
		(at 105.265474 -337.402932 90)
		(property "Reference" "R1231"
			(at 0 0 90)
			(layer "B.SilkS")
			(hide yes)
			(effects
				(font
					(size 1.27 1.27)
				)
				(justify mirror)
			)
		)
		(property "Value" ""
			(at 0 0 90)
			(layer "B.Fab")
			(effects
				(font
					(size 1.27 1.27)
				)
				(justify mirror)
			)
		)
		(duplicate_pad_numbers_are_jumpers no)
		(fp_line
			(start 0.7874 -0.4064)
			(end -0.7874 -0.4064)
			(stroke
				(width 0.1524)
				(type default)
			)
			(layer "B.SilkS")
		)
		(fp_line
			(start -0.7874 -0.4064)
			(end -0.7874 0.4064)
			(stroke
				(width 0.1524)
				(type default)
			)
			(layer "B.SilkS")
		)
		(fp_line
			(start 0.7874 0.4064)
			(end 0.7874 -0.4064)
			(stroke
				(width 0.1524)
				(type default)
			)
			(layer "B.SilkS")
		)
		(fp_line
			(start -0.7874 0.4064)
			(end 0.7874 0.4064)
			(stroke
				(width 0.1524)
				(type default)
			)
			(layer "B.SilkS")
		)
		(fp_line
			(start 0.67945 -0.305054)
			(end 0.12065 -0.305054)
			(stroke
				(width 0.1)
				(type default)
			)
			(layer "B.Fab")
		)
		(fp_line
			(start 0.12065 -0.305054)
			(end 0.12065 -0.2794)
			(stroke
				(width 0.1)
				(type default)
			)
			(layer "B.Fab")
		)
		(fp_line
			(start -0.12065 -0.3048)
			(end -0.67945 -0.3048)
			(stroke
				(width 0.1)
				(type default)
			)
			(layer "B.Fab")
		)
		(fp_line
			(start -0.67945 -0.3048)
			(end -0.67945 0.3048)
			(stroke
				(width 0.1)
				(type default)
			)
			(layer "B.Fab")
		)
		(fp_line
			(start 0.12065 -0.2794)
			(end -0.12065 -0.2794)
			(stroke
				(width 0.1)
				(type default)
			)
			(layer "B.Fab")
		)
		(fp_line
			(start -0.12065 -0.2794)
			(end -0.12065 -0.3048)
			(stroke
				(width 0.1)
				(type default)
			)
			(layer "B.Fab")
		)
		(fp_line
			(start 0.12065 0.2794)
			(end 0.12065 0.3048)
			(stroke
				(width 0.1)
				(type default)
			)
			(layer "B.Fab")
		)
		(fp_line
			(start -0.120396 0.2794)
			(end 0.12065 0.2794)
			(stroke
				(width 0.1)
				(type default)
			)
			(layer "B.Fab")
		)
		(fp_line
			(start 0.67945 0.3048)
			(end 0.67945 -0.305054)
			(stroke
				(width 0.1)
				(type default)
			)
			(layer "B.Fab")
		)
		(fp_line
			(start 0.12065 0.3048)
			(end 0.67945 0.3048)
			(stroke
				(width 0.1)
				(type default)
			)
			(layer "B.Fab")
		)
		(fp_line
			(start -0.120396 0.3048)
			(end -0.120396 0.2794)
			(stroke
				(width 0.1)
				(type default)
			)
			(layer "B.Fab")
		)
		(fp_line
			(start -0.67945 0.3048)
			(end -0.120396 0.3048)
			(stroke
				(width 0.1)
				(type default)
			)
			(layer "B.Fab")
		)
		(pad "1" smd circle
			(at 0.40005 0 270)
			(size 0 0)
			(layers "B.Cu" "B.Mask" "B.Paste")
			(net "CLK_100M_DB800ZL_PEX3_S0_R_DP")
		)
		(pad "2" smd circle
			(at -0.40005 0 270)
			(size 0 0)
			(layers "B.Cu" "B.Mask" "B.Paste")
			(net "CLK_100M_DB800ZL_PEX3_S0_DP")
		)
	)
)
